(kicad_pcb
	(version 20260206)
	(generator "pcbnew")
	(generator_version "10.0")
	(general
		(thickness 1.6)
		(legacy_teardrops no)
	)
	(paper "A4")
	(title_block
		(title "01162023_DA0F0TEBIF0_F0T_Expander_BD_F_brd_V02_OCP.brd")
		(comment 1 "Grand Teton / footprints 5017-5022 of 9728")
	)
	(layers
		(0 "F.Cu" signal "TOP")
		(4 "In1.Cu" signal "GND")
		(6 "In2.Cu" signal "VCC")
		(8 "In3.Cu" signal "VCC1")
		(10 "In4.Cu" signal "GND1")
		(12 "In5.Cu" signal "IN1")
		(14 "In6.Cu" signal "GND2")
		(16 "In7.Cu" signal "IN2")
		(18 "In8.Cu" signal "GND3")
		(20 "In9.Cu" signal "IN3")
		(22 "In10.Cu" signal "GND4")
		(24 "In11.Cu" signal "IN4")
		(26 "In12.Cu" signal "GND5")
		(28 "In13.Cu" signal "IN5")
		(30 "In14.Cu" signal "GND6")
		(32 "In15.Cu" signal "IN6")
		(34 "In16.Cu" signal "GND7")
		(2 "B.Cu" signal "BOTTOM")
		(9 "F.Adhes" user "F.Adhesive")
		(11 "B.Adhes" user "B.Adhesive")
		(13 "F.Paste" user "Package Geometry/Pastemask Top")
		(15 "B.Paste" user "Package Geometry/Pastemask Bottom")
		(5 "F.SilkS" user "Ref Des/Silkscreen Top")
		(7 "B.SilkS" user "Ref Des/Silkscreen Bottom")
		(1 "F.Mask" user "Board Geometry/Soldermask Top")
		(3 "B.Mask" user "Board Geometry/Soldermask Bottom")
		(17 "Dwgs.User" user "User.Drawings")
		(19 "Cmts.User" user "User.Comments")
		(21 "Eco1.User" user "User.Eco1")
		(23 "Eco2.User" user "User.Eco2")
		(25 "Edge.Cuts" user "Board Geometry/Outline")
		(27 "Margin" user)
		(31 "F.CrtYd" user "Package Geometry/Place Bound Top")
		(29 "B.CrtYd" user "Package Geometry/Place Bound Bottom")
		(35 "F.Fab" user "Ref Des/Assembly Top")
		(33 "B.Fab" user "Ref Des/Assembly Bottom")
	)
	(footprint ""
		(layer "F.Cu")
		(at 310.334406 -87.599012)
		(property "Reference" "U35"
			(at -1.267206 -1.706118 0)
			(unlocked yes)
			(layer "F.SilkS")
			(effects
				(font
					(size 0.7874 0.5842)
					(thickness 0.1524)
				)
				(justify left)
			)
		)
		(property "Value" ""
			(at 0 0 0)
			(layer "F.Fab")
			(effects
				(font
					(size 1.27 1.27)
				)
			)
		)
		(duplicate_pad_numbers_are_jumpers no)
		(fp_line
			(start -1.684274 -1.074928)
			(end -0.381 -1.074928)
			(stroke
				(width 0.1524)
				(type default)
			)
			(layer "F.SilkS")
		)
		(fp_line
			(start -1.684274 1.074928)
			(end -1.684274 -1.074928)
			(stroke
				(width 0.1524)
				(type default)
			)
			(layer "F.SilkS")
		)
		(fp_line
			(start -0.381 -1.074928)
			(end 0 -0.625094)
			(stroke
				(width 0.1524)
				(type default)
			)
			(layer "F.SilkS")
		)
		(fp_line
			(start 0 -0.625094)
			(end 0.381 -1.074928)
			(stroke
				(width 0.1524)
				(type default)
			)
			(layer "F.SilkS")
		)
		(fp_line
			(start 0.381 -1.074928)
			(end 1.684274 -1.074928)
			(stroke
				(width 0.1524)
				(type default)
			)
			(layer "F.SilkS")
		)
		(fp_line
			(start 1.684274 -1.074928)
			(end 1.684274 1.074928)
			(stroke
				(width 0.1524)
				(type default)
			)
			(layer "F.SilkS")
		)
		(fp_line
			(start 1.684274 1.074928)
			(end -1.684274 1.074928)
			(stroke
				(width 0.1524)
				(type default)
			)
			(layer "F.SilkS")
		)
		(fp_poly
			(pts
				(xy -2.637282 -0.903986) (xy -2.637282 -0.395986) (xy -1.875282 -0.649986)
			)
			(stroke
				(width 0)
				(type default)
			)
			(fill yes)
			(layer "F.SilkS")
		)
		(fp_line
			(start -0.700024 -1.074928)
			(end -0.700024 1.074928)
			(stroke
				(width 0.1)
				(type default)
			)
			(layer "F.Fab")
		)
		(fp_line
			(start -0.700024 1.074928)
			(end 0.700024 1.074928)
			(stroke
				(width 0.1)
				(type default)
			)
			(layer "F.Fab")
		)
		(fp_line
			(start 0.700024 -1.074928)
			(end -0.700024 -1.074928)
			(stroke
				(width 0.1)
				(type default)
			)
			(layer "F.Fab")
		)
		(fp_line
			(start 0.700024 1.074928)
			(end 0.700024 -1.074928)
			(stroke
				(width 0.1)
				(type default)
			)
			(layer "F.Fab")
		)
		(fp_poly
			(pts
				(xy -2.637282 -0.903986) (xy -2.637282 -0.395986) (xy -1.875282 -0.649986)
			)
			(stroke
				(width 0)
				(type default)
			)
			(fill yes)
			(layer "F.Fab")
		)
		(pad "1" smd rect
			(at -1.100074 -0.649986 270)
			(size 0.4064 0.9144)
			(layers "F.Cu" "F.Mask" "F.Paste")
			(net "Net_8451")
		)
		(pad "2" smd rect
			(at -1.100074 0 270)
			(size 0.4064 0.9144)
			(layers "F.Cu" "F.Mask" "F.Paste")
			(net "RST_HP_NIC5_N")
		)
		(pad "3" smd rect
			(at -1.100074 0.649986 270)
			(size 0.4064 0.9144)
			(layers "F.Cu" "F.Mask" "F.Paste")
			(net "GND")
		)
		(pad "4" smd rect
			(at 1.100074 0.649986 270)
			(size 0.4064 0.9144)
			(layers "F.Cu" "F.Mask" "F.Paste")
			(net "RST_HP_NIC5_BUF_N")
		)
		(pad "5" smd rect
			(at 1.100074 -0.649986 270)
			(size 0.4064 0.9144)
			(layers "F.Cu" "F.Mask" "F.Paste")
			(net "P3V3_AUX")
		)
	)
	(footprint ""
		(layer "F.Cu")
		(at 247.322848 -182.394606 90)
		(property "Reference" "R5504"
			(at 0 0 90)
			(layer "F.SilkS")
			(hide yes)
			(effects
				(font
					(size 1.27 1.27)
				)
			)
		)
		(property "Value" ""
			(at 0 0 90)
			(layer "F.Fab")
			(effects
				(font
					(size 1.27 1.27)
				)
			)
		)
		(duplicate_pad_numbers_are_jumpers no)
		(fp_line
			(start 0.7874 -0.4064)
			(end 0.7874 0.4064)
			(stroke
				(width 0.1524)
				(type default)
			)
			(layer "F.SilkS")
		)
		(fp_line
			(start -0.7874 -0.4064)
			(end 0.7874 -0.4064)
			(stroke
				(width 0.1524)
				(type default)
			)
			(layer "F.SilkS")
		)
		(fp_line
			(start 0.7874 0.4064)
			(end -0.7874 0.4064)
			(stroke
				(width 0.1524)
				(type default)
			)
			(layer "F.SilkS")
		)
		(fp_line
			(start -0.7874 0.4064)
			(end -0.7874 -0.4064)
			(stroke
				(width 0.1524)
				(type default)
			)
			(layer "F.SilkS")
		)
		(fp_line
			(start -0.12065 -0.305054)
			(end -0.12065 -0.2794)
			(stroke
				(width 0.1)
				(type default)
			)
			(layer "F.Fab")
		)
		(fp_line
			(start -0.67945 -0.305054)
			(end -0.12065 -0.305054)
			(stroke
				(width 0.1)
				(type default)
			)
			(layer "F.Fab")
		)
		(fp_line
			(start 0.67945 -0.3048)
			(end 0.67945 0.3048)
			(stroke
				(width 0.1)
				(type default)
			)
			(layer "F.Fab")
		)
		(fp_line
			(start 0.12065 -0.3048)
			(end 0.67945 -0.3048)
			(stroke
				(width 0.1)
				(type default)
			)
			(layer "F.Fab")
		)
		(fp_line
			(start 0.12065 -0.2794)
			(end 0.12065 -0.3048)
			(stroke
				(width 0.1)
				(type default)
			)
			(layer "F.Fab")
		)
		(fp_line
			(start -0.12065 -0.2794)
			(end 0.12065 -0.2794)
			(stroke
				(width 0.1)
				(type default)
			)
			(layer "F.Fab")
		)
		(fp_line
			(start 0.120396 0.2794)
			(end -0.12065 0.2794)
			(stroke
				(width 0.1)
				(type default)
			)
			(layer "F.Fab")
		)
		(fp_line
			(start -0.12065 0.2794)
			(end -0.12065 0.3048)
			(stroke
				(width 0.1)
				(type default)
			)
			(layer "F.Fab")
		)
		(fp_line
			(start 0.67945 0.3048)
			(end 0.120396 0.3048)
			(stroke
				(width 0.1)
				(type default)
			)
			(layer "F.Fab")
		)
		(fp_line
			(start 0.120396 0.3048)
			(end 0.120396 0.2794)
			(stroke
				(width 0.1)
				(type default)
			)
			(layer "F.Fab")
		)
		(fp_line
			(start -0.12065 0.3048)
			(end -0.67945 0.3048)
			(stroke
				(width 0.1)
				(type default)
			)
			(layer "F.Fab")
		)
		(fp_line
			(start -0.67945 0.3048)
			(end -0.67945 -0.305054)
			(stroke
				(width 0.1)
				(type default)
			)
			(layer "F.Fab")
		)
		(pad "1" smd circle
			(at -0.40005 0 90)
			(size 0 0)
			(layers "F.Cu" "F.Mask" "F.Paste")
			(net "BIC_FWSPICK_R")
		)
		(pad "2" smd circle
			(at 0.40005 0 90)
			(size 0 0)
			(layers "F.Cu" "F.Mask" "F.Paste")
			(net "P3V3_AUX")
		)
	)
	(footprint ""
		(layer "F.Cu")
		(at 428.837852 -343.952322 90)
		(property "Reference" "C809"
			(at 0 0 90)
			(layer "F.SilkS")
			(hide yes)
			(effects
				(font
					(size 1.27 1.27)
				)
			)
		)
		(property "Value" ""
			(at 0 0 90)
			(layer "F.Fab")
			(effects
				(font
					(size 1.27 1.27)
				)
			)
		)
		(duplicate_pad_numbers_are_jumpers no)
		(fp_line
			(start 0.299974 -0.150114)
			(end 0.299974 0.150114)
			(stroke
				(width 0.1)
				(type default)
			)
			(layer "F.Fab")
		)
		(fp_line
			(start -0.299974 -0.150114)
			(end 0.299974 -0.150114)
			(stroke
				(width 0.1)
				(type default)
			)
			(layer "F.Fab")
		)
		(fp_line
			(start 0.299974 0.150114)
			(end -0.299974 0.150114)
			(stroke
				(width 0.1)
				(type default)
			)
			(layer "F.Fab")
		)
		(fp_line
			(start -0.299974 0.150114)
			(end -0.299974 -0.150114)
			(stroke
				(width 0.1)
				(type default)
			)
			(layer "F.Fab")
		)
		(pad "1" smd rect
			(at -0.2667 0 90)
			(size 0.3048 0.381)
			(layers "F.Cu" "F.Mask" "F.Paste")
			(net "P5E_PEX3_STN7_TX_DN<120>")
		)
		(pad "2" smd rect
			(at 0.2667 0 90)
			(size 0.3048 0.381)
			(layers "F.Cu" "F.Mask" "F.Paste")
			(net "P5E_PEX3_STN7_TX_C_DN<120>")
		)
	)
	(footprint ""
		(layer "F.Cu")
		(at 428.83963 -159.235648 180)
		(property "Reference" "R399"
			(at 0 0 180)
			(layer "F.SilkS")
			(hide yes)
			(effects
				(font
					(size 1.27 1.27)
				)
			)
		)
		(property "Value" ""
			(at 0 0 180)
			(layer "F.Fab")
			(effects
				(font
					(size 1.27 1.27)
				)
			)
		)
		(duplicate_pad_numbers_are_jumpers no)
		(fp_line
			(start 0.7874 0.4064)
			(end -0.7874 0.4064)
			(stroke
				(width 0.1524)
				(type default)
			)
			(layer "F.SilkS")
		)
		(fp_line
			(start 0.7874 -0.4064)
			(end 0.7874 0.4064)
			(stroke
				(width 0.1524)
				(type default)
			)
			(layer "F.SilkS")
		)
		(fp_line
			(start -0.7874 0.4064)
			(end -0.7874 -0.4064)
			(stroke
				(width 0.1524)
				(type default)
			)
			(layer "F.SilkS")
		)
		(fp_line
			(start -0.7874 -0.4064)
			(end 0.7874 -0.4064)
			(stroke
				(width 0.1524)
				(type default)
			)
			(layer "F.SilkS")
		)
		(fp_line
			(start 0.67945 0.3048)
			(end 0.120396 0.3048)
			(stroke
				(width 0.1)
				(type default)
			)
			(layer "F.Fab")
		)
		(fp_line
			(start 0.67945 -0.3048)
			(end 0.67945 0.3048)
			(stroke
				(width 0.1)
				(type default)
			)
			(layer "F.Fab")
		)
		(fp_line
			(start 0.12065 -0.2794)
			(end 0.12065 -0.3048)
			(stroke
				(width 0.1)
				(type default)
			)
			(layer "F.Fab")
		)
		(fp_line
			(start 0.12065 -0.3048)
			(end 0.67945 -0.3048)
			(stroke
				(width 0.1)
				(type default)
			)
			(layer "F.Fab")
		)
		(fp_line
			(start 0.120396 0.3048)
			(end 0.120396 0.2794)
			(stroke
				(width 0.1)
				(type default)
			)
			(layer "F.Fab")
		)
		(fp_line
			(start 0.120396 0.2794)
			(end -0.12065 0.2794)
			(stroke
				(width 0.1)
				(type default)
			)
			(layer "F.Fab")
		)
		(fp_line
			(start -0.12065 0.3048)
			(end -0.67945 0.3048)
			(stroke
				(width 0.1)
				(type default)
			)
			(layer "F.Fab")
		)
		(fp_line
			(start -0.12065 0.2794)
			(end -0.12065 0.3048)
			(stroke
				(width 0.1)
				(type default)
			)
			(layer "F.Fab")
		)
		(fp_line
			(start -0.12065 -0.2794)
			(end 0.12065 -0.2794)
			(stroke
				(width 0.1)
				(type default)
			)
			(layer "F.Fab")
		)
		(fp_line
			(start -0.12065 -0.305054)
			(end -0.12065 -0.2794)
			(stroke
				(width 0.1)
				(type default)
			)
			(layer "F.Fab")
		)
		(fp_line
			(start -0.67945 0.3048)
			(end -0.67945 -0.305054)
			(stroke
				(width 0.1)
				(type default)
			)
			(layer "F.Fab")
		)
		(fp_line
			(start -0.67945 -0.305054)
			(end -0.12065 -0.305054)
			(stroke
				(width 0.1)
				(type default)
			)
			(layer "F.Fab")
		)
		(pad "1" smd circle
			(at -0.40005 0 180)
			(size 0 0)
			(layers "F.Cu" "F.Mask" "F.Paste")
			(net "PRSNT_NIC7_N")
		)
		(pad "2" smd circle
			(at 0.40005 0 180)
			(size 0 0)
			(layers "F.Cu" "F.Mask" "F.Paste")
			(net "PRSNTB3_NIC7_N")
		)
	)
	(footprint ""
		(layer "F.Cu")
		(at 363.959902 -397.42618 -90)
		(property "Reference" "R6703"
			(at 0 0 270)
			(layer "F.SilkS")
			(hide yes)
			(effects
				(font
					(size 1.27 1.27)
				)
			)
		)
		(property "Value" ""
			(at 0 0 270)
			(layer "F.Fab")
			(effects
				(font
					(size 1.27 1.27)
				)
			)
		)
		(duplicate_pad_numbers_are_jumpers no)
		(fp_line
			(start -0.7874 0.4064)
			(end -0.7874 -0.4064)
			(stroke
				(width 0.1524)
				(type default)
			)
			(layer "F.SilkS")
		)
		(fp_line
			(start 0.7874 0.4064)
			(end -0.7874 0.4064)
			(stroke
				(width 0.1524)
				(type default)
			)
			(layer "F.SilkS")
		)
		(fp_line
			(start -0.7874 -0.4064)
			(end 0.7874 -0.4064)
			(stroke
				(width 0.1524)
				(type default)
			)
			(layer "F.SilkS")
		)
		(fp_line
			(start 0.7874 -0.4064)
			(end 0.7874 0.4064)
			(stroke
				(width 0.1524)
				(type default)
			)
			(layer "F.SilkS")
		)
		(fp_line
			(start -0.67945 0.3048)
			(end -0.67945 -0.305054)
			(stroke
				(width 0.1)
				(type default)
			)
			(layer "F.Fab")
		)
		(fp_line
			(start -0.12065 0.3048)
			(end -0.67945 0.3048)
			(stroke
				(width 0.1)
				(type default)
			)
			(layer "F.Fab")
		)
		(fp_line
			(start 0.120396 0.3048)
			(end 0.120396 0.2794)
			(stroke
				(width 0.1)
				(type default)
			)
			(layer "F.Fab")
		)
		(fp_line
			(start 0.67945 0.3048)
			(end 0.120396 0.3048)
			(stroke
				(width 0.1)
				(type default)
			)
			(layer "F.Fab")
		)
		(fp_line
			(start -0.12065 0.2794)
			(end -0.12065 0.3048)
			(stroke
				(width 0.1)
				(type default)
			)
			(layer "F.Fab")
		)
		(fp_line
			(start 0.120396 0.2794)
			(end -0.12065 0.2794)
			(stroke
				(width 0.1)
				(type default)
			)
			(layer "F.Fab")
		)
		(fp_line
			(start -0.12065 -0.2794)
			(end 0.12065 -0.2794)
			(stroke
				(width 0.1)
				(type default)
			)
			(layer "F.Fab")
		)
		(fp_line
			(start 0.12065 -0.2794)
			(end 0.12065 -0.3048)
			(stroke
				(width 0.1)
				(type default)
			)
			(layer "F.Fab")
		)
		(fp_line
			(start 0.12065 -0.3048)
			(end 0.67945 -0.3048)
			(stroke
				(width 0.1)
				(type default)
			)
			(layer "F.Fab")
		)
		(fp_line
			(start 0.67945 -0.3048)
			(end 0.67945 0.3048)
			(stroke
				(width 0.1)
				(type default)
			)
			(layer "F.Fab")
		)
		(fp_line
			(start -0.67945 -0.305054)
			(end -0.12065 -0.305054)
			(stroke
				(width 0.1)
				(type default)
			)
			(layer "F.Fab")
		)
		(fp_line
			(start -0.12065 -0.305054)
			(end -0.12065 -0.2794)
			(stroke
				(width 0.1)
				(type default)
			)
			(layer "F.Fab")
		)
		(pad "1" smd circle
			(at -0.40005 0 270)
			(size 0 0)
			(layers "F.Cu" "F.Mask" "F.Paste")
			(net "P3V3_AUX")
		)
		(pad "2" smd circle
			(at 0.40005 0 270)
			(size 0 0)
			(layers "F.Cu" "F.Mask" "F.Paste")
			(net "MB_3V3IO_RSVD3")
		)
	)
	(footprint ""
		(layer "F.Cu")
		(at 450.683376 -49.94148)
		(property "Reference" "R5909"
			(at 0 0 0)
			(layer "F.SilkS")
			(hide yes)
			(effects
				(font
					(size 1.27 1.27)
				)
			)
		)
		(property "Value" ""
			(at 0 0 0)
			(layer "F.Fab")
			(effects
				(font
					(size 1.27 1.27)
				)
			)
		)
		(duplicate_pad_numbers_are_jumpers no)
		(fp_line
			(start -0.7874 -0.4064)
			(end 0.7874 -0.4064)
			(stroke
				(width 0.1524)
				(type default)
			)
			(layer "F.SilkS")
		)
		(fp_line
			(start -0.7874 0.4064)
			(end -0.7874 -0.4064)
			(stroke
				(width 0.1524)
				(type default)
			)
			(layer "F.SilkS")
		)
		(fp_line
			(start 0.7874 -0.4064)
			(end 0.7874 0.4064)
			(stroke
				(width 0.1524)
				(type default)
			)
			(layer "F.SilkS")
		)
		(fp_line
			(start 0.7874 0.4064)
			(end -0.7874 0.4064)
			(stroke
				(width 0.1524)
				(type default)
			)
			(layer "F.SilkS")
		)
		(fp_line
			(start -0.67945 -0.305054)
			(end -0.12065 -0.305054)
			(stroke
				(width 0.1)
				(type default)
			)
			(layer "F.Fab")
		)
		(fp_line
			(start -0.67945 0.3048)
			(end -0.67945 -0.305054)
			(stroke
				(width 0.1)
				(type default)
			)
			(layer "F.Fab")
		)
		(fp_line
			(start -0.12065 -0.305054)
			(end -0.12065 -0.2794)
			(stroke
				(width 0.1)
				(type default)
			)
			(layer "F.Fab")
		)
		(fp_line
			(start -0.12065 -0.2794)
			(end 0.12065 -0.2794)
			(stroke
				(width 0.1)
				(type default)
			)
			(layer "F.Fab")
		)
		(fp_line
			(start -0.12065 0.2794)
			(end -0.12065 0.3048)
			(stroke
				(width 0.1)
				(type default)
			)
			(layer "F.Fab")
		)
		(fp_line
			(start -0.12065 0.3048)
			(end -0.67945 0.3048)
			(stroke
				(width 0.1)
				(type default)
			)
			(layer "F.Fab")
		)
		(fp_line
			(start 0.120396 0.2794)
			(end -0.12065 0.2794)
			(stroke
				(width 0.1)
				(type default)
			)
			(layer "F.Fab")
		)
		(fp_line
			(start 0.120396 0.3048)
			(end 0.120396 0.2794)
			(stroke
				(width 0.1)
				(type default)
			)
			(layer "F.Fab")
		)
		(fp_line
			(start 0.12065 -0.3048)
			(end 0.67945 -0.3048)
			(stroke
				(width 0.1)
				(type default)
			)
			(layer "F.Fab")
		)
		(fp_line
			(start 0.12065 -0.2794)
			(end 0.12065 -0.3048)
			(stroke
				(width 0.1)
				(type default)
			)
			(layer "F.Fab")
		)
		(fp_line
			(start 0.67945 -0.3048)
			(end 0.67945 0.3048)
			(stroke
				(width 0.1)
				(type default)
			)
			(layer "F.Fab")
		)
		(fp_line
			(start 0.67945 0.3048)
			(end 0.120396 0.3048)
			(stroke
				(width 0.1)
				(type default)
			)
			(layer "F.Fab")
		)
		(pad "1" smd circle
			(at -0.40005 0)
			(size 0 0)
			(layers "F.Cu" "F.Mask" "F.Paste")
			(net "SSD15_ADC_A0")
		)
		(pad "2" smd circle
			(at 0.40005 0)
			(size 0 0)
			(layers "F.Cu" "F.Mask" "F.Paste")
			(net "SMB_SSD15_ADC_SCL")
		)
	)
)
